(kicad_pcb
	(version 20241229)
	(generator "pcbnew")
	(generator_version "9.0")
	(general
		(thickness 1.294)
		(legacy_teardrops no)
	)
	(paper "A3")
	(title_block
		(title "Kintex 410T devboard")
		(date "2024-04-03")
		(rev "1.1.2")
		(comment 9 "footprints 50-55 of 975")
	)
	(layers
		(0 "F.Cu" mixed)
		(4 "In1.Cu" power)
		(6 "In2.Cu" power)
		(8 "In3.Cu" mixed)
		(10 "In4.Cu" power)
		(12 "In5.Cu" mixed)
		(14 "In6.Cu" power)
		(16 "In7.Cu" mixed)
		(18 "In8.Cu" power)
		(2 "B.Cu" mixed)
		(9 "F.Adhes" user "F.Adhesive")
		(11 "B.Adhes" user "B.Adhesive")
		(13 "F.Paste" user)
		(15 "B.Paste" user)
		(5 "F.SilkS" user "F.Silkscreen")
		(7 "B.SilkS" user "B.Silkscreen")
		(1 "F.Mask" user)
		(3 "B.Mask" user)
		(17 "Dwgs.User" user "User.Drawings")
		(19 "Cmts.User" user "User.Comments")
		(21 "Eco1.User" user "User.Eco1")
		(23 "Eco2.User" user "User.Eco2")
		(25 "Edge.Cuts" user)
		(27 "Margin" user)
		(31 "F.CrtYd" user "F.Courtyard")
		(29 "B.CrtYd" user "B.Courtyard")
		(35 "F.Fab" user)
		(33 "B.Fab" user)
	)
	(footprint "antmicro-footprints:R_0402_1005Metric"
		(layer "F.Cu")
		(at 159 184 90)
		(descr "Resistor SMD 0402")
		(tags "resistor SMD 0402")
		(property "Reference" "R365"
			(at 0.7 0.4 90)
			(layer "F.SilkS")
			(effects
				(font
					(size 0.7 0.7)
					(thickness 0.15)
				)
				(justify left bottom)
			)
		)
		(property "Value" "R_0R_0402"
			(at 0 1.4 90)
			(layer "F.Fab")
			(effects
				(font
					(size 0.7 0.7)
					(thickness 0.15)
				)
				(justify left bottom)
			)
		)
		(property "Description" "SMD Chip Resistor, Jumper, 0 ohm, 100 mW, 0402 [1005 Metric], Thick Film, General Purpose"
			(at 0 0 90)
			(layer "F.Fab")
			(hide yes)
			(effects
				(font
					(size 1.27 1.27)
					(thickness 0.15)
				)
			)
		)
		(property "Author" "Antmicro"
			(at 343 25 0)
			(layer "F.Fab")
			(hide yes)
			(effects
				(font
					(size 1 1)
					(thickness 0.15)
				)
			)
		)
		(property "Current" "1A"
			(at 343 25 0)
			(layer "F.Fab")
			(hide yes)
			(effects
				(font
					(size 1 1)
					(thickness 0.15)
				)
			)
		)
		(property "DNP" "DNP"
			(at 343 25 0)
			(layer "F.Fab")
			(hide yes)
			(effects
				(font
					(size 1 1)
					(thickness 0.15)
				)
			)
		)
		(property "License" "Apache-2.0"
			(at 343 25 0)
			(layer "F.Fab")
			(hide yes)
			(effects
				(font
					(size 1 1)
					(thickness 0.15)
				)
			)
		)
		(property "MPN" "ERJ2GE0R00X"
			(at 343 25 0)
			(layer "F.Fab")
			(hide yes)
			(effects
				(font
					(size 1 1)
					(thickness 0.15)
				)
			)
		)
		(property "Manufacturer" "Panasonic"
			(at 343 25 0)
			(layer "F.Fab")
			(hide yes)
			(effects
				(font
					(size 1 1)
					(thickness 0.15)
				)
			)
		)
		(property "Tolerance" ""
			(at 343 25 0)
			(layer "F.Fab")
			(hide yes)
			(effects
				(font
					(size 1 1)
					(thickness 0.15)
				)
			)
		)
		(property "Val" "0R"
			(at 343 25 0)
			(layer "F.Fab")
			(hide yes)
			(effects
				(font
					(size 1 1)
					(thickness 0.15)
				)
			)
		)
		(property "dnp" ""
			(at 343 25 0)
			(layer "F.Fab")
			(hide yes)
			(effects
				(font
					(size 1 1)
					(thickness 0.15)
				)
			)
		)
		(property "exclude_from_bom" ""
			(at 343 25 0)
			(layer "F.Fab")
			(hide yes)
			(effects
				(font
					(size 1 1)
					(thickness 0.15)
				)
			)
		)
		(sheetname "FPGA Bank 12 & 13")
		(sheetfile "fpga-bank-12-13.kicad_sch")
		(attr smd exclude_from_bom)
		(fp_rect
			(start -0.925 -0.47)
			(end 0.925 0.47)
			(stroke
				(width 0.05)
				(type default)
			)
			(fill no)
			(layer "F.CrtYd")
		)
		(fp_rect
			(start -0.5 -0.25)
			(end 0.5 0.25)
			(stroke
				(width 0.15)
				(type solid)
			)
			(fill no)
			(layer "F.Fab")
		)
		(pad "1" smd roundrect
			(at -0.48 0 90)
			(size 0.59 0.64)
			(layers "F.Cu" "F.Mask" "F.Paste")
			(roundrect_rratio 0.25)
			(net 571 "/FPGA Bank 12 & 13/~{PB_CTRL_CLR}")
			(pintype "passive")
		)
		(pad "2" smd roundrect
			(at 0.48 0 90)
			(size 0.59 0.64)
			(layers "F.Cu" "F.Mask" "F.Paste")
			(roundrect_rratio 0.25)
			(net 279 "/DC-DC Converters/PB_CTRL.~{PB_CTRL_CLR}")
			(pintype "passive")
		)
	)
	(footprint "antmicro-footprints:C_0402_1005Metric"
		(layer "F.Cu")
		(at 173.570001 126.510001 180)
		(descr "Capacitor SMD 0402")
		(tags "capacitor SMD 0402")
		(property "Reference" "C310"
			(at -3.729999 -0.389999 0)
			(layer "F.SilkS")
			(effects
				(font
					(size 0.7 0.7)
					(thickness 0.15)
				)
				(justify right bottom)
			)
		)
		(property "Value" "C_100n_0402"
			(at 0 1.4 0)
			(layer "F.Fab")
			(effects
				(font
					(size 0.7 0.7)
					(thickness 0.15)
				)
				(justify right bottom)
			)
		)
		(property "Description" "SMD Multilayer Ceramic Capacitor, 0.1 µF, 50 V, 0402 [1005 Metric], ± 10%, X5R, GRM Series"
			(at 0 0 180)
			(layer "F.Fab")
			(hide yes)
			(effects
				(font
					(size 1.27 1.27)
					(thickness 0.15)
				)
			)
		)
		(property "Author" "Antmicro"
			(at 347.140002 253.020002 0)
			(layer "F.Fab")
			(hide yes)
			(effects
				(font
					(size 1 1)
					(thickness 0.15)
				)
			)
		)
		(property "Dielectric" "X5R"
			(at 347.140002 253.020002 0)
			(layer "F.Fab")
			(hide yes)
			(effects
				(font
					(size 1 1)
					(thickness 0.15)
				)
			)
		)
		(property "License" "Apache-2.0"
			(at 347.140002 253.020002 0)
			(layer "F.Fab")
			(hide yes)
			(effects
				(font
					(size 1 1)
					(thickness 0.15)
				)
			)
		)
		(property "MPN" "GRM155R61H104KE14D"
			(at 347.140002 253.020002 0)
			(layer "F.Fab")
			(hide yes)
			(effects
				(font
					(size 1 1)
					(thickness 0.15)
				)
			)
		)
		(property "Manufacturer" "Murata"
			(at 347.140002 253.020002 0)
			(layer "F.Fab")
			(hide yes)
			(effects
				(font
					(size 1 1)
					(thickness 0.15)
				)
			)
		)
		(property "Val" "100n"
			(at 347.140002 253.020002 0)
			(layer "F.Fab")
			(hide yes)
			(effects
				(font
					(size 1 1)
					(thickness 0.15)
				)
			)
		)
		(property "Voltage" "50V"
			(at 347.140002 253.020002 0)
			(layer "F.Fab")
			(hide yes)
			(effects
				(font
					(size 1 1)
					(thickness 0.15)
				)
			)
		)
		(sheetname "FMC+ HSPC")
		(sheetfile "fmc-hspc.kicad_sch")
		(attr smd)
		(fp_rect
			(start -0.925 -0.47)
			(end 0.925 0.47)
			(stroke
				(width 0.05)
				(type default)
			)
			(fill no)
			(layer "F.CrtYd")
		)
		(fp_line
			(start 0.504 0.248)
			(end -0.494 0.248)
			(stroke
				(width 0.15)
				(type solid)
			)
			(layer "F.Fab")
		)
		(fp_line
			(start 0.504 -0.25)
			(end 0.504 0.248)
			(stroke
				(width 0.15)
				(type solid)
			)
			(layer "F.Fab")
		)
		(fp_line
			(start -0.494 0.248)
			(end -0.494 -0.25)
			(stroke
				(width 0.15)
				(type solid)
			)
			(layer "F.Fab")
		)
		(fp_line
			(start -0.494 -0.25)
			(end 0.504 -0.25)
			(stroke
				(width 0.15)
				(type solid)
			)
			(layer "F.Fab")
		)
		(pad "1" smd roundrect
			(at -0.48 0 180)
			(size 0.59 0.64)
			(layers "F.Cu" "F.Mask" "F.Paste")
			(roundrect_rratio 0.25)
			(net 107 "/FMC+ HSPC/GTX115.TX1_P")
			(pintype "passive")
		)
		(pad "2" smd roundrect
			(at 0.48 0 180)
			(size 0.59 0.64)
			(layers "F.Cu" "F.Mask" "F.Paste")
			(roundrect_rratio 0.25)
			(net 105 "/FMC+ HSPC/GTX_TX6_C_P")
			(pintype "passive")
		)
	)
	(footprint "antmicro-footprints:C_0402_1005Metric"
		(layer "F.Cu")
		(at 168.7 151.2)
		(descr "Capacitor SMD 0402")
		(tags "capacitor SMD 0402")
		(property "Reference" "C189"
			(at -1.85 1.3 0)
			(layer "F.SilkS")
			(effects
				(font
					(size 0.7 0.7)
					(thickness 0.15)
				)
				(justify left bottom)
			)
		)
		(property "Value" "C_10u_0402"
			(at 0 1.4 0)
			(layer "F.Fab")
			(effects
				(font
					(size 0.7 0.7)
					(thickness 0.15)
				)
				(justify left bottom)
			)
		)
		(property "Description" "SMD Multilayer Ceramic Capacitor, 10 µF, 6.3 V, 0402 [1005 Metric], ± 20%, X5R, CC Series"
			(at 0 0 0)
			(layer "F.Fab")
			(hide yes)
			(effects
				(font
					(size 1.27 1.27)
					(thickness 0.15)
				)
			)
		)
		(property "Author" "Antmicro"
			(at 0 0 0)
			(layer "F.Fab")
			(hide yes)
			(effects
				(font
					(size 1 1)
					(thickness 0.15)
				)
			)
		)
		(property "Dielectric" ""
			(at 0 0 0)
			(layer "F.Fab")
			(hide yes)
			(effects
				(font
					(size 1 1)
					(thickness 0.15)
				)
			)
		)
		(property "License" "Apache-2.0"
			(at 0 0 0)
			(layer "F.Fab")
			(hide yes)
			(effects
				(font
					(size 1 1)
					(thickness 0.15)
				)
			)
		)
		(property "MPN" "CC0402MRX5R5BB106"
			(at 0 0 0)
			(layer "F.Fab")
			(hide yes)
			(effects
				(font
					(size 1 1)
					(thickness 0.15)
				)
			)
		)
		(property "Manufacturer" "YAGEO"
			(at 0 0 0)
			(layer "F.Fab")
			(hide yes)
			(effects
				(font
					(size 1 1)
					(thickness 0.15)
				)
			)
		)
		(property "Val" "10u"
			(at 0 0 0)
			(layer "F.Fab")
			(hide yes)
			(effects
				(font
					(size 1 1)
					(thickness 0.15)
				)
			)
		)
		(property "Voltage" ""
			(at 0 0 0)
			(layer "F.Fab")
			(hide yes)
			(effects
				(font
					(size 1 1)
					(thickness 0.15)
				)
			)
		)
		(sheetname "DRAM + SRAM")
		(sheetfile "ram.kicad_sch")
		(attr smd)
		(fp_rect
			(start -0.925 -0.47)
			(end 0.925 0.47)
			(stroke
				(width 0.05)
				(type default)
			)
			(fill no)
			(layer "F.CrtYd")
		)
		(fp_line
			(start -0.494 -0.25)
			(end 0.504 -0.25)
			(stroke
				(width 0.15)
				(type solid)
			)
			(layer "F.Fab")
		)
		(fp_line
			(start -0.494 0.248)
			(end -0.494 -0.25)
			(stroke
				(width 0.15)
				(type solid)
			)
			(layer "F.Fab")
		)
		(fp_line
			(start 0.504 -0.25)
			(end 0.504 0.248)
			(stroke
				(width 0.15)
				(type solid)
			)
			(layer "F.Fab")
		)
		(fp_line
			(start 0.504 0.248)
			(end -0.494 0.248)
			(stroke
				(width 0.15)
				(type solid)
			)
			(layer "F.Fab")
		)
		(pad "1" smd roundrect
			(at -0.48 0)
			(size 0.59 0.64)
			(layers "F.Cu" "F.Mask" "F.Paste")
			(roundrect_rratio 0.25)
			(net 1 "GND")
			(pintype "passive")
		)
		(pad "2" smd roundrect
			(at 0.48 0)
			(size 0.59 0.64)
			(layers "F.Cu" "F.Mask" "F.Paste")
			(roundrect_rratio 0.25)
			(net 25 "+1V35")
			(pintype "passive")
		)
	)
	(footprint "antmicro-footprints:R_0402_1005Metric"
		(layer "F.Cu")
		(at 225.1 115.2)
		(descr "Resistor SMD 0402")
		(tags "resistor SMD 0402")
		(property "Reference" "R103"
			(at -3.65 0.4 0)
			(layer "F.SilkS")
			(effects
				(font
					(size 0.7 0.7)
					(thickness 0.15)
				)
				(justify left bottom)
			)
		)
		(property "Value" "R_0R_0402"
			(at 0 1.4 0)
			(layer "F.Fab")
			(effects
				(font
					(size 0.7 0.7)
					(thickness 0.15)
				)
				(justify left bottom)
			)
		)
		(property "Description" "SMD Chip Resistor, Jumper, 0 ohm, 100 mW, 0402 [1005 Metric], Thick Film, General Purpose"
			(at 0 0 0)
			(layer "F.Fab")
			(hide yes)
			(effects
				(font
					(size 1.27 1.27)
					(thickness 0.15)
				)
			)
		)
		(property "Author" "Antmicro"
			(at 0 0 0)
			(layer "F.Fab")
			(hide yes)
			(effects
				(font
					(size 1 1)
					(thickness 0.15)
				)
			)
		)
		(property "Current" "1A"
			(at 0 0 0)
			(layer "F.Fab")
			(hide yes)
			(effects
				(font
					(size 1 1)
					(thickness 0.15)
				)
			)
		)
		(property "License" "Apache-2.0"
			(at 0 0 0)
			(layer "F.Fab")
			(hide yes)
			(effects
				(font
					(size 1 1)
					(thickness 0.15)
				)
			)
		)
		(property "MPN" "ERJ2GE0R00X"
			(at 0 0 0)
			(layer "F.Fab")
			(hide yes)
			(effects
				(font
					(size 1 1)
					(thickness 0.15)
				)
			)
		)
		(property "Manufacturer" "Panasonic"
			(at 0 0 0)
			(layer "F.Fab")
			(hide yes)
			(effects
				(font
					(size 1 1)
					(thickness 0.15)
				)
			)
		)
		(property "Tolerance" ""
			(at 0 0 0)
			(layer "F.Fab")
			(hide yes)
			(effects
				(font
					(size 1 1)
					(thickness 0.15)
				)
			)
		)
		(property "Val" "0R"
			(at 0 0 0)
			(layer "F.Fab")
			(hide yes)
			(effects
				(font
					(size 1 1)
					(thickness 0.15)
				)
			)
		)
		(sheetname "SPI Flash + SD Card")
		(sheetfile "spi-flash.kicad_sch")
		(attr smd)
		(fp_rect
			(start -0.925 -0.47)
			(end 0.925 0.47)
			(stroke
				(width 0.05)
				(type default)
			)
			(fill no)
			(layer "F.CrtYd")
		)
		(fp_rect
			(start -0.5 -0.25)
			(end 0.5 0.25)
			(stroke
				(width 0.15)
				(type solid)
			)
			(fill no)
			(layer "F.Fab")
		)
		(pad "1" smd roundrect
			(at -0.48 0)
			(size 0.59 0.64)
			(layers "F.Cu" "F.Mask" "F.Paste")
			(roundrect_rratio 0.25)
			(net 419 "/FPGA Bank 16 & 17/USR_FLASH_1.DQ2")
			(pintype "passive")
		)
		(pad "2" smd roundrect
			(at 0.48 0)
			(size 0.59 0.64)
			(layers "F.Cu" "F.Mask" "F.Paste")
			(roundrect_rratio 0.25)
			(net 910 "/SPI Flash + SD Card/USR_FLASH_1_DQ2")
			(pintype "passive")
		)
	)
	(footprint "antmicro-footprints:C_0402_1005Metric"
		(layer "F.Cu")
		(at 207.403752 97.5615 180)
		(descr "Capacitor SMD 0402")
		(tags "capacitor SMD 0402")
		(property "Reference" "C255"
			(at -1.096248 7.1615 0)
			(layer "F.SilkS")
			(effects
				(font
					(size 0.7 0.7)
					(thickness 0.15)
				)
				(justify right bottom)
			)
		)
		(property "Value" "C_10u_0402"
			(at 0 1.4 0)
			(layer "F.Fab")
			(effects
				(font
					(size 0.7 0.7)
					(thickness 0.15)
				)
				(justify right bottom)
			)
		)
		(property "Description" "SMD Multilayer Ceramic Capacitor, 10 µF, 6.3 V, 0402 [1005 Metric], ± 20%, X5R, CC Series"
			(at 0 0 180)
			(layer "F.Fab")
			(hide yes)
			(effects
				(font
					(size 1.27 1.27)
					(thickness 0.15)
				)
			)
		)
		(property "Author" "Antmicro"
			(at 414.807504 195.123 0)
			(layer "F.Fab")
			(hide yes)
			(effects
				(font
					(size 1 1)
					(thickness 0.15)
				)
			)
		)
		(property "Dielectric" ""
			(at 414.807504 195.123 0)
			(layer "F.Fab")
			(hide yes)
			(effects
				(font
					(size 1 1)
					(thickness 0.15)
				)
			)
		)
		(property "License" "Apache-2.0"
			(at 414.807504 195.123 0)
			(layer "F.Fab")
			(hide yes)
			(effects
				(font
					(size 1 1)
					(thickness 0.15)
				)
			)
		)
		(property "MPN" "CC0402MRX5R5BB106"
			(at 414.807504 195.123 0)
			(layer "F.Fab")
			(hide yes)
			(effects
				(font
					(size 1 1)
					(thickness 0.15)
				)
			)
		)
		(property "Manufacturer" "YAGEO"
			(at 414.807504 195.123 0)
			(layer "F.Fab")
			(hide yes)
			(effects
				(font
					(size 1 1)
					(thickness 0.15)
				)
			)
		)
		(property "Val" "10u"
			(at 414.807504 195.123 0)
			(layer "F.Fab")
			(hide yes)
			(effects
				(font
					(size 1 1)
					(thickness 0.15)
				)
			)
		)
		(property "Voltage" ""
			(at 414.807504 195.123 0)
			(layer "F.Fab")
			(hide yes)
			(effects
				(font
					(size 1 1)
					(thickness 0.15)
				)
			)
		)
		(sheetname "HDMI + Ethernet")
		(sheetfile "hdmi-ethernet.kicad_sch")
		(attr smd)
		(fp_rect
			(start -0.925 -0.47)
			(end 0.925 0.47)
			(stroke
				(width 0.05)
				(type default)
			)
			(fill no)
			(layer "F.CrtYd")
		)
		(fp_line
			(start 0.504 0.248)
			(end -0.494 0.248)
			(stroke
				(width 0.15)
				(type solid)
			)
			(layer "F.Fab")
		)
		(fp_line
			(start 0.504 -0.25)
			(end 0.504 0.248)
			(stroke
				(width 0.15)
				(type solid)
			)
			(layer "F.Fab")
		)
		(fp_line
			(start -0.494 0.248)
			(end -0.494 -0.25)
			(stroke
				(width 0.15)
				(type solid)
			)
			(layer "F.Fab")
		)
		(fp_line
			(start -0.494 -0.25)
			(end 0.504 -0.25)
			(stroke
				(width 0.15)
				(type solid)
			)
			(layer "F.Fab")
		)
		(pad "1" smd roundrect
			(at -0.48 0 180)
			(size 0.59 0.64)
			(layers "F.Cu" "F.Mask" "F.Paste")
			(roundrect_rratio 0.25)
			(net 1 "GND")
			(pintype "passive")
		)
		(pad "2" smd roundrect
			(at 0.48 0 180)
			(size 0.59 0.64)
			(layers "F.Cu" "F.Mask" "F.Paste")
			(roundrect_rratio 0.25)
			(net 717 "/HDMI + Ethernet/GBE_AVDDH")
			(pintype "passive")
		)
	)
	(footprint "antmicro-footprints:R_0603_1608Metric"
		(layer "F.Cu")
		(at 161.5 161.5 90)
		(descr "Resistor SMD 0603")
		(tags "resistor SMD 0603")
		(property "Reference" "R286"
			(at -1.48 1.42 90)
			(layer "F.SilkS")
			(effects
				(font
					(size 0.7 0.7)
					(thickness 0.15)
				)
				(justify left bottom)
			)
		)
		(property "Value" "R_0R_22.4A_0603"
			(at 0 1.6 90)
			(layer "F.Fab")
			(effects
				(font
					(size 0.7 0.7)
					(thickness 0.15)
				)
				(justify left bottom)
			)
		)
		(property "Description" "SMD Chip Resistor"
			(at 0 0 90)
			(layer "F.Fab")
			(hide yes)
			(effects
				(font
					(size 1.27 1.27)
					(thickness 0.15)
				)
			)
		)
		(property "Author" "Antmicro"
			(at 323 0 0)
			(layer "F.Fab")
			(hide yes)
			(effects
				(font
					(size 1 1)
					(thickness 0.15)
				)
			)
		)
		(property "License" "Apache-2.0"
			(at 323 0 0)
			(layer "F.Fab")
			(hide yes)
			(effects
				(font
					(size 1 1)
					(thickness 0.15)
				)
			)
		)
		(property "MPN" "PMR03EZPJ000"
			(at 323 0 0)
			(layer "F.Fab")
			(hide yes)
			(effects
				(font
					(size 1 1)
					(thickness 0.15)
				)
			)
		)
		(property "Manufacturer" "ROHM Semiconductor"
			(at 323 0 0)
			(layer "F.Fab")
			(hide yes)
			(effects
				(font
					(size 1 1)
					(thickness 0.15)
				)
			)
		)
		(property "Max. Curr." "22.4A"
			(at 323 0 0)
			(layer "F.Fab")
			(hide yes)
			(effects
				(font
					(size 1 1)
					(thickness 0.15)
				)
			)
		)
		(property "Tolerance" "template_tolerance"
			(at 323 0 0)
			(layer "F.Fab")
			(hide yes)
			(effects
				(font
					(size 1 1)
					(thickness 0.15)
				)
			)
		)
		(property "Val" "0R"
			(at 323 0 0)
			(layer "F.Fab")
			(hide yes)
			(effects
				(font
					(size 1 1)
					(thickness 0.15)
				)
			)
		)
		(sheetname "DC-DC Converters")
		(sheetfile "dc-dc.kicad_sch")
		(attr smd)
		(fp_line
			(start -0.15 -0.4)
			(end 0.15 -0.4)
			(stroke
				(width 0.15)
				(type solid)
			)
			(layer "F.SilkS")
		)
		(fp_line
			(start -0.15 0.4)
			(end 0.15 0.4)
			(stroke
				(width 0.15)
				(type solid)
			)
			(layer "F.SilkS")
		)
		(fp_rect
			(start -1.25 -0.65)
			(end 1.25 0.65)
			(stroke
				(width 0.05)
				(type solid)
			)
			(fill no)
			(layer "F.CrtYd")
		)
		(fp_rect
			(start -0.8 -0.4)
			(end 0.8 0.4)
			(stroke
				(width 0.15)
				(type solid)
			)
			(fill no)
			(layer "F.Fab")
		)
		(pad "1" smd roundrect
			(at -0.7 0 90)
			(size 0.8 1)
			(layers "F.Cu" "F.Mask" "F.Paste")
			(roundrect_rratio 0.2)
			(net 734 "/DC-DC Converters/1V8_local")
			(pintype "passive")
		)
		(pad "2" smd roundrect
			(at 0.7 0 90)
			(size 0.8 1)
			(layers "F.Cu" "F.Mask" "F.Paste")
			(roundrect_rratio 0.2)
			(net 26 "+1V8")
			(pintype "passive")
		)
	)
)
